(kicad_pcb
	(version 20221018)
	(generator pcbnew)
	(general
    (thickness 1.62)
  )
	(paper "A4")
	(title_block
    (title "ECP5 - Datacenter Secure Control Module (DC-SCM)")
    (date "2024-07-01")
    (rev "1.2.1")
		(comment 9 "footprints 459-466 of 506")
	)
	(layers
    (0 "F.Cu" signal)
    (1 "In1.Cu" power)
    (2 "In2.Cu" signal)
    (3 "In3.Cu" power)
    (4 "In4.Cu" power)
    (5 "In5.Cu" signal)
    (6 "In6.Cu" power)
    (31 "B.Cu" signal)
    (32 "B.Adhes" user "B.Adhesive")
    (33 "F.Adhes" user "F.Adhesive")
    (34 "B.Paste" user)
    (35 "F.Paste" user)
    (36 "B.SilkS" user "B.Silkscreen")
    (37 "F.SilkS" user "F.Silkscreen")
    (38 "B.Mask" user)
    (39 "F.Mask" user)
    (40 "Dwgs.User" user "User.Drawings")
    (41 "Cmts.User" user "User.Comments")
    (42 "Eco1.User" user "User.Eco1")
    (43 "Eco2.User" user "User.Eco2")
    (44 "Edge.Cuts" user)
    (45 "Margin" user)
    (46 "B.CrtYd" user "B.Courtyard")
    (47 "F.CrtYd" user "F.Courtyard")
    (48 "B.Fab" user)
    (49 "F.Fab" user)
  )
	(footprint "antmicro-footprints:C_0402_1005Metric" (layer "B.Cu")
    (at 122.45 122.45 180)
    (descr "Capacitor SMD 0402")
    (tags "capacitor SMD 0402")
    (property "Author" "Antmicro")
    (property "Dielectric" "X5R")
    (property "License" "Apache-2.0")
    (property "MPN" "GRM155R61H104KE14D")
    (property "Manufacturer" "Murata")
    (property "Public" "False")
    (property "Sheetfile" "interfaces.kicad_sch")
    (property "Sheetname" "Interfaces")
    (property "Val" "100n")
    (property "Voltage" "50V")
    (property "ki_description" "SMD Multilayer Ceramic Capacitor, 0.1 µF, 50 V, 0402 [1005 Metric], ± 10%, X5R, GRM Series")
    (property "ki_keywords" "0402, SMT, CAPACITOR, PASSIVE, CERAMIC, MLCC")
    (attr smd)
    (fp_text reference "C61" (at 1.97 -0.025) (layer "B.SilkS")
        (effects (font (size 0.7 0.7) (thickness 0.127)) (justify mirror))
    )
    (fp_text value "C_100n_0402" (at 0 -1.17) (layer "B.Fab")
        (effects (font (size 1 1) (thickness 0.15)) (justify mirror))
    )
    (fp_text user "Author: Antmicro" (at -0.939 -3.399) (layer "B.Fab") hide
        (effects (font (size 0.7 0.7) (thickness 0.15)) (justify left bottom mirror))
    )
    (fp_text user "${REFERENCE}" (at 0 0) (layer "B.Fab")
        (effects (font (size 0.25 0.25) (thickness 0.04)) (justify mirror))
    )
    (fp_text user "License: Apache-2.0" (at -0.939 -5.799) (layer "B.Fab") hide
        (effects (font (size 0.7 0.7) (thickness 0.15)) (justify left bottom mirror))
    )
    (fp_rect (start -0.925 0.47) (end 0.925 -0.47)
      (stroke (width 0.05) (type default)) (fill none) (layer "B.CrtYd"))
    (fp_line (start -0.494 -0.248) (end -0.494 0.25)
      (stroke (width 0.15) (type solid)) (layer "B.Fab"))
    (fp_line (start -0.494 0.25) (end 0.504 0.25)
      (stroke (width 0.15) (type solid)) (layer "B.Fab"))
    (fp_line (start 0.504 -0.248) (end -0.494 -0.248)
      (stroke (width 0.15) (type solid)) (layer "B.Fab"))
    (fp_line (start 0.504 0.25) (end 0.504 -0.248)
      (stroke (width 0.15) (type solid)) (layer "B.Fab"))
    (pad "1" smd roundrect (at -0.48 0 180) (size 0.59 0.64) (layers "B.Cu" "B.Paste" "B.Mask") (roundrect_rratio 0.25)
      (net 2 "VCC3V3") (pintype "passive"))
    (pad "2" smd roundrect (at 0.48 0 180) (size 0.59 0.64) (layers "B.Cu" "B.Paste" "B.Mask") (roundrect_rratio 0.25)
      (net 1 "GND") (pintype "passive"))
  )
	(footprint "antmicro-footprints:C_0402_1005Metric" (layer "B.Cu")
    (at 127.2 129.7)
    (descr "Capacitor SMD 0402")
    (tags "capacitor SMD 0402")
    (property "Author" "Antmicro")
    (property "Dielectric" "X5R")
    (property "License" "Apache-2.0")
    (property "MPN" "GRM155R61H104KE14D")
    (property "Manufacturer" "Murata")
    (property "Public" "False")
    (property "Sheetfile" "interfaces.kicad_sch")
    (property "Sheetname" "Interfaces")
    (property "Val" "100n")
    (property "Voltage" "50V")
    (property "ki_description" "SMD Multilayer Ceramic Capacitor, 0.1 µF, 50 V, 0402 [1005 Metric], ± 10%, X5R, GRM Series")
    (property "ki_keywords" "0402, SMT, CAPACITOR, PASSIVE, CERAMIC, MLCC")
    (attr smd)
    (fp_text reference "C65" (at -0.02 -0.965) (layer "B.SilkS")
        (effects (font (size 0.7 0.7) (thickness 0.127)) (justify mirror))
    )
    (fp_text value "C_100n_0402" (at 0 -1.17) (layer "B.Fab")
        (effects (font (size 1 1) (thickness 0.15)) (justify mirror))
    )
    (fp_text user "Author: Antmicro" (at -0.939 -3.399 180) (layer "B.Fab") hide
        (effects (font (size 0.7 0.7) (thickness 0.15)) (justify left bottom mirror))
    )
    (fp_text user "License: Apache-2.0" (at -0.939 -5.799 180) (layer "B.Fab") hide
        (effects (font (size 0.7 0.7) (thickness 0.15)) (justify left bottom mirror))
    )
    (fp_text user "${REFERENCE}" (at 0 0) (layer "B.Fab")
        (effects (font (size 0.25 0.25) (thickness 0.04)) (justify mirror))
    )
    (fp_rect (start -0.925 0.47) (end 0.925 -0.47)
      (stroke (width 0.05) (type default)) (fill none) (layer "B.CrtYd"))
    (fp_line (start -0.494 -0.248) (end -0.494 0.25)
      (stroke (width 0.15) (type solid)) (layer "B.Fab"))
    (fp_line (start -0.494 0.25) (end 0.504 0.25)
      (stroke (width 0.15) (type solid)) (layer "B.Fab"))
    (fp_line (start 0.504 -0.248) (end -0.494 -0.248)
      (stroke (width 0.15) (type solid)) (layer "B.Fab"))
    (fp_line (start 0.504 0.25) (end 0.504 -0.248)
      (stroke (width 0.15) (type solid)) (layer "B.Fab"))
    (pad "1" smd roundrect (at -0.48 0) (size 0.59 0.64) (layers "B.Cu" "B.Paste" "B.Mask") (roundrect_rratio 0.25)
      (net 2 "VCC3V3") (pintype "passive"))
    (pad "2" smd roundrect (at 0.48 0) (size 0.59 0.64) (layers "B.Cu" "B.Paste" "B.Mask") (roundrect_rratio 0.25)
      (net 1 "GND") (pintype "passive"))
  )
	(footprint "antmicro-footprints:C_0402_1005Metric" (layer "B.Cu")
    (at 123.2 124.15 180)
    (descr "Capacitor SMD 0402")
    (tags "capacitor SMD 0402")
    (property "Author" "Antmicro")
    (property "Dielectric" "X5R")
    (property "License" "Apache-2.0")
    (property "MPN" "GRM155R61H104KE14D")
    (property "Manufacturer" "Murata")
    (property "Public" "False")
    (property "Sheetfile" "interfaces.kicad_sch")
    (property "Sheetname" "Interfaces")
    (property "Val" "100n")
    (property "Voltage" "50V")
    (property "ki_description" "SMD Multilayer Ceramic Capacitor, 0.1 µF, 50 V, 0402 [1005 Metric], ± 10%, X5R, GRM Series")
    (property "ki_keywords" "0402, SMT, CAPACITOR, PASSIVE, CERAMIC, MLCC")
    (attr smd)
    (fp_text reference "C71" (at 0.02 -1.035) (layer "B.SilkS")
        (effects (font (size 0.7 0.7) (thickness 0.127)) (justify mirror))
    )
    (fp_text value "C_100n_0402" (at 0 -1.17) (layer "B.Fab")
        (effects (font (size 1 1) (thickness 0.15)) (justify mirror))
    )
    (fp_text user "Author: Antmicro" (at -0.939 -3.399) (layer "B.Fab") hide
        (effects (font (size 0.7 0.7) (thickness 0.15)) (justify left bottom mirror))
    )
    (fp_text user "${REFERENCE}" (at 0 0) (layer "B.Fab")
        (effects (font (size 0.25 0.25) (thickness 0.04)) (justify mirror))
    )
    (fp_text user "License: Apache-2.0" (at -0.939 -5.799) (layer "B.Fab") hide
        (effects (font (size 0.7 0.7) (thickness 0.15)) (justify left bottom mirror))
    )
    (fp_rect (start -0.925 0.47) (end 0.925 -0.47)
      (stroke (width 0.05) (type default)) (fill none) (layer "B.CrtYd"))
    (fp_line (start -0.494 -0.248) (end -0.494 0.25)
      (stroke (width 0.15) (type solid)) (layer "B.Fab"))
    (fp_line (start -0.494 0.25) (end 0.504 0.25)
      (stroke (width 0.15) (type solid)) (layer "B.Fab"))
    (fp_line (start 0.504 -0.248) (end -0.494 -0.248)
      (stroke (width 0.15) (type solid)) (layer "B.Fab"))
    (fp_line (start 0.504 0.25) (end 0.504 -0.248)
      (stroke (width 0.15) (type solid)) (layer "B.Fab"))
    (pad "1" smd roundrect (at -0.48 0 180) (size 0.59 0.64) (layers "B.Cu" "B.Paste" "B.Mask") (roundrect_rratio 0.25)
      (net 227 "Net-(C71-Pad1)") (pintype "passive"))
    (pad "2" smd roundrect (at 0.48 0 180) (size 0.59 0.64) (layers "B.Cu" "B.Paste" "B.Mask") (roundrect_rratio 0.25)
      (net 1 "GND") (pintype "passive"))
  )
	(footprint "antmicro-footprints:C_0402_1005Metric" (layer "B.Cu")
    (at 122.515 129.2)
    (descr "Capacitor SMD 0402")
    (tags "capacitor SMD 0402")
    (property "Author" "Antmicro")
    (property "Dielectric" "")
    (property "License" "Apache-2.0")
    (property "MPN" "GRM155R61A475MEAAD")
    (property "Manufacturer" "Murata")
    (property "Public" "False")
    (property "Sheetfile" "interfaces.kicad_sch")
    (property "Sheetname" "Interfaces")
    (property "Val" "4u7")
    (property "Voltage" "")
    (property "ki_description" "SMD Multilayer Ceramic Capacitor, 4.7 µF, 10 V, 0402 [1005 Metric], ± 20%, X5R, GRM Series")
    (property "ki_keywords" "0402, SMT, CAPACITOR, PASSIVE")
    (attr smd)
    (fp_text reference "C68" (at -2.01 0) (layer "B.SilkS")
        (effects (font (size 0.7 0.7) (thickness 0.127)) (justify mirror))
    )
    (fp_text value "C_4u7_0402" (at 0 -1.17) (layer "B.Fab")
        (effects (font (size 1 1) (thickness 0.15)) (justify mirror))
    )
    (fp_text user "Author: Antmicro" (at -0.939 -3.399 180) (layer "B.Fab") hide
        (effects (font (size 0.7 0.7) (thickness 0.15)) (justify left bottom mirror))
    )
    (fp_text user "${REFERENCE}" (at 0 0) (layer "B.Fab")
        (effects (font (size 0.25 0.25) (thickness 0.04)) (justify mirror))
    )
    (fp_text user "License: Apache-2.0" (at -0.939 -5.799 180) (layer "B.Fab") hide
        (effects (font (size 0.7 0.7) (thickness 0.15)) (justify left bottom mirror))
    )
    (fp_rect (start -0.925 0.47) (end 0.925 -0.47)
      (stroke (width 0.05) (type default)) (fill none) (layer "B.CrtYd"))
    (fp_line (start -0.494 -0.248) (end -0.494 0.25)
      (stroke (width 0.15) (type solid)) (layer "B.Fab"))
    (fp_line (start -0.494 0.25) (end 0.504 0.25)
      (stroke (width 0.15) (type solid)) (layer "B.Fab"))
    (fp_line (start 0.504 -0.248) (end -0.494 -0.248)
      (stroke (width 0.15) (type solid)) (layer "B.Fab"))
    (fp_line (start 0.504 0.25) (end 0.504 -0.248)
      (stroke (width 0.15) (type solid)) (layer "B.Fab"))
    (pad "1" smd roundrect (at -0.48 0) (size 0.59 0.64) (layers "B.Cu" "B.Paste" "B.Mask") (roundrect_rratio 0.25)
      (net 1 "GND") (pintype "passive"))
    (pad "2" smd roundrect (at 0.48 0) (size 0.59 0.64) (layers "B.Cu" "B.Paste" "B.Mask") (roundrect_rratio 0.25)
      (net 2 "VCC3V3") (pintype "passive"))
  )
	(footprint "antmicro-footprints:C_0402_1005Metric" (layer "B.Cu")
    (at 122.95 112.45 180)
    (descr "Capacitor SMD 0402")
    (tags "capacitor SMD 0402")
    (property "Author" "Antmicro")
    (property "Dielectric" "X5R")
    (property "License" "Apache-2.0")
    (property "MPN" "GRM155R61H104KE14D")
    (property "Manufacturer" "Murata")
    (property "Public" "False")
    (property "Sheetfile" "interfaces.kicad_sch")
    (property "Sheetname" "Interfaces")
    (property "Val" "100n")
    (property "Voltage" "50V")
    (property "ki_description" "SMD Multilayer Ceramic Capacitor, 0.1 µF, 50 V, 0402 [1005 Metric], ± 10%, X5R, GRM Series")
    (property "ki_keywords" "0402, SMT, CAPACITOR, PASSIVE, CERAMIC, MLCC")
    (attr smd)
    (fp_text reference "C62" (at -0.1 -1.2) (layer "B.SilkS")
        (effects (font (size 0.7 0.7) (thickness 0.127)) (justify mirror))
    )
    (fp_text value "C_100n_0402" (at 0 -1.17) (layer "B.Fab")
        (effects (font (size 1 1) (thickness 0.15)) (justify mirror))
    )
    (fp_text user "License: Apache-2.0" (at -0.939 -5.799) (layer "B.Fab") hide
        (effects (font (size 0.7 0.7) (thickness 0.15)) (justify left bottom mirror))
    )
    (fp_text user "Author: Antmicro" (at -0.939 -3.399) (layer "B.Fab") hide
        (effects (font (size 0.7 0.7) (thickness 0.15)) (justify left bottom mirror))
    )
    (fp_text user "${REFERENCE}" (at 0 0) (layer "B.Fab")
        (effects (font (size 0.25 0.25) (thickness 0.04)) (justify mirror))
    )
    (fp_rect (start -0.925 0.47) (end 0.925 -0.47)
      (stroke (width 0.05) (type default)) (fill none) (layer "B.CrtYd"))
    (fp_line (start -0.494 -0.248) (end -0.494 0.25)
      (stroke (width 0.15) (type solid)) (layer "B.Fab"))
    (fp_line (start -0.494 0.25) (end 0.504 0.25)
      (stroke (width 0.15) (type solid)) (layer "B.Fab"))
    (fp_line (start 0.504 -0.248) (end -0.494 -0.248)
      (stroke (width 0.15) (type solid)) (layer "B.Fab"))
    (fp_line (start 0.504 0.25) (end 0.504 -0.248)
      (stroke (width 0.15) (type solid)) (layer "B.Fab"))
    (pad "1" smd roundrect (at -0.48 0 180) (size 0.59 0.64) (layers "B.Cu" "B.Paste" "B.Mask") (roundrect_rratio 0.25)
      (net 2 "VCC3V3") (pintype "passive"))
    (pad "2" smd roundrect (at 0.48 0 180) (size 0.59 0.64) (layers "B.Cu" "B.Paste" "B.Mask") (roundrect_rratio 0.25)
      (net 1 "GND") (pintype "passive"))
  )
	(footprint "antmicro-footprints:R_0402_1005Metric" (layer "B.Cu")
    (at 83.05 87.55 180)
    (descr "Resistor SMD 0402")
    (tags "resistor SMD 0402")
    (property "Author" "Antmicro")
    (property "License" "Apache-2.0")
    (property "MPN" "CR0402-FX-1002GLF")
    (property "Manufacturer" "Bourns")
    (property "Public" "False")
    (property "Sheetfile" "power-supply.kicad_sch")
    (property "Sheetname" "Power supply")
    (property "Tolerance" "1%")
    (property "Val" "10k")
    (property "ki_description" "SMD Chip Resistor, 10 kohm, ± 1%, 62.5 mW, 0402 [1005 Metric], Thick Film, General Purpose")
    (property "ki_keywords" "0402, SMT, RESISTOR, PASSIVE")
    (attr smd)
    (fp_text reference "R103" (at 0 1.17 180) (layer "B.SilkS")
        (effects (font (size 0.7 0.7) (thickness 0.127)) (justify mirror))
    )
    (fp_text value "R_10k_0402" (at 0 -1.17 180) (layer "B.Fab")
        (effects (font (size 1 1) (thickness 0.15)) (justify mirror))
    )
    (fp_text user "License: Apache-2.0" (at -0.95 -5.169) (layer "B.Fab") hide
        (effects (font (size 0.7 0.7) (thickness 0.15)) (justify left bottom mirror))
    )
    (fp_text user "${REFERENCE}" (at 0 0 180) (layer "B.Fab")
        (effects (font (size 0.25 0.25) (thickness 0.04)) (justify mirror))
    )
    (fp_text user "Author: Antmicro" (at -0.95 -4.169) (layer "B.Fab") hide
        (effects (font (size 0.7 0.7) (thickness 0.15)) (justify left bottom mirror))
    )
    (fp_rect (start -0.925 0.47) (end 0.925 -0.47)
      (stroke (width 0.05) (type default)) (fill none) (layer "B.CrtYd"))
    (fp_rect (start -0.5 0.25) (end 0.5 -0.25)
      (stroke (width 0.15) (type solid)) (fill none) (layer "B.Fab"))
    (pad "1" smd roundrect (at -0.48 0 180) (size 0.59 0.64) (layers "B.Cu" "B.Paste" "B.Mask") (roundrect_rratio 0.25)
      (net 11 "VCC5V0") (pintype "passive"))
    (pad "2" smd roundrect (at 0.48 0 180) (size 0.59 0.64) (layers "B.Cu" "B.Paste" "B.Mask") (roundrect_rratio 0.25)
      (net 222 "/Power supply/3V3_PG") (pintype "passive"))
  )
	(footprint "antmicro-footprints:C_0402_1005Metric" (layer "B.Cu")
    (at 88.865 116.92 -90)
    (descr "Capacitor SMD 0402")
    (tags "capacitor SMD 0402")
    (property "Author" "Antmicro")
    (property "Dielectric" "")
    (property "License" "Apache-2.0")
    (property "MPN" "C1005X5R1E474M050BB")
    (property "Manufacturer" "TDK")
    (property "Public" "False")
    (property "Sheetfile" "ddr3.kicad_sch")
    (property "Sheetname" "DDR3")
    (property "Val" "470n")
    (property "Voltage" "")
    (property "ki_description" "SMD Multilayer Ceramic Capacitor, 0.47 µF, 25 V, 0402 [1005 Metric], ± 20%, X5R, C")
    (property "ki_keywords" "0402, SMT, CAPACITOR, PASSIVE, CERAMIC, MLCC")
    (attr smd)
    (fp_text reference "C90" (at 0 1.17 90) (layer "B.SilkS")
        (effects (font (size 0.7 0.7) (thickness 0.127)) (justify mirror))
    )
    (fp_text value "C_470n_0402" (at 0 -1.17 90) (layer "B.Fab")
        (effects (font (size 1 1) (thickness 0.15)) (justify mirror))
    )
    (fp_text user "License: Apache-2.0" (at -0.939 -5.799 90) (layer "B.Fab") hide
        (effects (font (size 0.7 0.7) (thickness 0.15)) (justify left bottom mirror))
    )
    (fp_text user "Author: Antmicro" (at -0.939 -3.399 90) (layer "B.Fab") hide
        (effects (font (size 0.7 0.7) (thickness 0.15)) (justify left bottom mirror))
    )
    (fp_text user "${REFERENCE}" (at 0 0 90) (layer "B.Fab")
        (effects (font (size 0.25 0.25) (thickness 0.04)) (justify mirror))
    )
    (fp_rect (start -0.925 0.47) (end 0.925 -0.47)
      (stroke (width 0.05) (type default)) (fill none) (layer "B.CrtYd"))
    (fp_line (start -0.494 -0.248) (end -0.494 0.25)
      (stroke (width 0.15) (type solid)) (layer "B.Fab"))
    (fp_line (start -0.494 0.25) (end 0.504 0.25)
      (stroke (width 0.15) (type solid)) (layer "B.Fab"))
    (fp_line (start 0.504 -0.248) (end -0.494 -0.248)
      (stroke (width 0.15) (type solid)) (layer "B.Fab"))
    (fp_line (start 0.504 0.25) (end 0.504 -0.248)
      (stroke (width 0.15) (type solid)) (layer "B.Fab"))
    (pad "1" smd roundrect (at -0.48 0 270) (size 0.59 0.64) (layers "B.Cu" "B.Paste" "B.Mask") (roundrect_rratio 0.25)
      (net 1 "GND") (pintype "passive"))
    (pad "2" smd roundrect (at 0.48 0 270) (size 0.59 0.64) (layers "B.Cu" "B.Paste" "B.Mask") (roundrect_rratio 0.25)
      (net 3 "VCC1V35") (pintype "passive"))
  )
	(footprint "antmicro-footprints:C_0402_1005Metric" (layer "B.Cu")
    (at 79.05 124.7 90)
    (descr "Capacitor SMD 0402")
    (tags "capacitor SMD 0402")
    (property "Author" "Antmicro")
    (property "Dielectric" "")
    (property "License" "Apache-2.0")
    (property "MPN" "C1005X5R1E474M050BB")
    (property "Manufacturer" "TDK")
    (property "Public" "False")
    (property "Sheetfile" "ddr3.kicad_sch")
    (property "Sheetname" "DDR3")
    (property "Val" "470n")
    (property "Voltage" "")
    (property "ki_description" "SMD Multilayer Ceramic Capacitor, 0.47 µF, 25 V, 0402 [1005 Metric], ± 20%, X5R, C")
    (property "ki_keywords" "0402, SMT, CAPACITOR, PASSIVE, CERAMIC, MLCC")
    (attr smd)
    (fp_text reference "C87" (at 0.035 -2.58 90) (layer "B.SilkS")
        (effects (font (size 0.7 0.7) (thickness 0.127)) (justify mirror))
    )
    (fp_text value "C_470n_0402" (at 0 -1.17 90) (layer "B.Fab")
        (effects (font (size 1 1) (thickness 0.15)) (justify mirror))
    )
    (fp_text user "License: Apache-2.0" (at -0.939 -5.799 270) (layer "B.Fab") hide
        (effects (font (size 0.7 0.7) (thickness 0.15)) (justify left bottom mirror))
    )
    (fp_text user "${REFERENCE}" (at 0 0 90) (layer "B.Fab")
        (effects (font (size 0.25 0.25) (thickness 0.04)) (justify mirror))
    )
    (fp_text user "Author: Antmicro" (at -0.939 -3.399 270) (layer "B.Fab") hide
        (effects (font (size 0.7 0.7) (thickness 0.15)) (justify left bottom mirror))
    )
    (fp_rect (start -0.925 0.47) (end 0.925 -0.47)
      (stroke (width 0.05) (type default)) (fill none) (layer "B.CrtYd"))
    (fp_line (start -0.494 -0.248) (end -0.494 0.25)
      (stroke (width 0.15) (type solid)) (layer "B.Fab"))
    (fp_line (start -0.494 0.25) (end 0.504 0.25)
      (stroke (width 0.15) (type solid)) (layer "B.Fab"))
    (fp_line (start 0.504 -0.248) (end -0.494 -0.248)
      (stroke (width 0.15) (type solid)) (layer "B.Fab"))
    (fp_line (start 0.504 0.25) (end 0.504 -0.248)
      (stroke (width 0.15) (type solid)) (layer "B.Fab"))
    (pad "1" smd roundrect (at -0.48 0 90) (size 0.59 0.64) (layers "B.Cu" "B.Paste" "B.Mask") (roundrect_rratio 0.25)
      (net 1 "GND") (pintype "passive"))
    (pad "2" smd roundrect (at 0.48 0 90) (size 0.59 0.64) (layers "B.Cu" "B.Paste" "B.Mask") (roundrect_rratio 0.25)
      (net 3 "VCC1V35") (pintype "passive"))
  )
)
